# T6G (Grand Teton) — schematic netlist excerpt (pin names and nets, part order shuffled) for the footprints in the layout excerpt that follows; sources: Cadence DE-HDL packaged netlist, KiCad conversion of 04192023_DAF0TMB3IC0_F0TG_MB_C_brd_V02_OCP.brd

R1005  Q_RES  33 5% CHIP  pkg 0402LF  page 155 : A = M2_0_PEWAKE_R_N ; B = IRQ_LVC3_WAKE_N
R3434  Q_RES  4.7K 5% CHIP  pkg 0402LF  page 126 : A = P3V3_AUX ; B = GPU_HMC_PRSNT
PC2242  Q_CAP  22UF 16V 20% X6S  pkg C0805  page 152 : A = P12V_SCM_R ; B = GND

(kicad_pcb
	(version 20260206)
	(generator "pcbnew")
	(generator_version "10.0")
	(general
		(thickness 1.6)
		(legacy_teardrops no)
	)
	(paper "A4")
	(title_block
		(title "04192023_DAF0TMB3IC0_F0TG_MB_C_brd_V02_OCP.brd")
		(comment 1 "Grand Teton / footprints 4379-4381 of 8354")
	)
	(layers
		(0 "F.Cu" signal "TOP")
		(4 "In1.Cu" signal "GND")
		(6 "In2.Cu" signal "IN1")
		(8 "In3.Cu" signal "GND1")
		(10 "In4.Cu" signal "IN2")
		(12 "In5.Cu" signal "GND2")
		(14 "In6.Cu" signal "IN3")
		(16 "In7.Cu" signal "GND3")
		(18 "In8.Cu" signal "VCC")
		(20 "In9.Cu" signal "VCC1")
		(22 "In10.Cu" signal "GND4")
		(24 "In11.Cu" signal "IN4")
		(26 "In12.Cu" signal "GND5")
		(28 "In13.Cu" signal "IN5")
		(30 "In14.Cu" signal "GND6")
		(32 "In15.Cu" signal "IN6")
		(34 "In16.Cu" signal "GND7")
		(2 "B.Cu" signal "BOTTOM")
		(9 "F.Adhes" user "F.Adhesive")
		(11 "B.Adhes" user "B.Adhesive")
		(13 "F.Paste" user "Package Geometry/Pastemask Top")
		(15 "B.Paste" user "Package Geometry/Pastemask Bottom")
		(5 "F.SilkS" user "Ref Des/Silkscreen Top")
		(7 "B.SilkS" user "Ref Des/Silkscreen Bottom")
		(1 "F.Mask" user "Board Geometry/Soldermask Top")
		(3 "B.Mask" user "Board Geometry/Soldermask Bottom")
		(17 "Dwgs.User" user "User.Drawings")
		(19 "Cmts.User" user "User.Comments")
		(21 "Eco1.User" user "User.Eco1")
		(23 "Eco2.User" user "User.Eco2")
		(25 "Edge.Cuts" user "Board Geometry/Outline")
		(27 "Margin" user)
		(31 "F.CrtYd" user "Package Geometry/Place Bound Top")
		(29 "B.CrtYd" user "Package Geometry/Place Bound Bottom")
		(35 "F.Fab" user "Ref Des/Assembly Top")
		(33 "B.Fab" user "Ref Des/Assembly Bottom")
	)
	(footprint ""
		(layer "F.Cu")
		(at 175.06188 -21.173948 180)
		(property "Reference" "PC2242"
			(at 0 0 180)
			(layer "F.SilkS")
			(hide yes)
			(effects
				(font
					(size 1.27 1.27)
				)
			)
		)
		(property "Value" ""
			(at 0 0 180)
			(layer "F.Fab")
			(effects
				(font
					(size 1.27 1.27)
				)
			)
		)
		(duplicate_pad_numbers_are_jumpers no)
		(fp_line
			(start 1.524 0.762)
			(end -1.524 0.762)
			(stroke
				(width 0.1524)
				(type default)
			)
			(layer "F.SilkS")
		)
		(fp_line
			(start 1.524 -0.762)
			(end 1.524 0.762)
			(stroke
				(width 0.1524)
				(type default)
			)
			(layer "F.SilkS")
		)
		(fp_line
			(start -1.524 0.762)
			(end -1.524 -0.762)
			(stroke
				(width 0.1524)
				(type default)
			)
			(layer "F.SilkS")
		)
		(fp_line
			(start -1.524 -0.762)
			(end 1.524 -0.762)
			(stroke
				(width 0.1524)
				(type default)
			)
			(layer "F.SilkS")
		)
		(fp_line
			(start 1.1049 0.724916)
			(end 1.1049 -0.724916)
			(stroke
				(width 0.1)
				(type default)
			)
			(layer "F.Fab")
		)
		(fp_line
			(start 1.1049 -0.724916)
			(end -1.1049 -0.724916)
			(stroke
				(width 0.1)
				(type default)
			)
			(layer "F.Fab")
		)
		(fp_line
			(start -1.1049 0.724916)
			(end 1.1049 0.724916)
			(stroke
				(width 0.1)
				(type default)
			)
			(layer "F.Fab")
		)
		(fp_line
			(start -1.1049 -0.724916)
			(end -1.1049 0.724916)
			(stroke
				(width 0.1)
				(type default)
			)
			(layer "F.Fab")
		)
		(pad "1" smd rect
			(at -0.889 0)
			(size 1.016 1.27)
			(layers "F.Cu" "F.Mask" "F.Paste")
			(net "P12V_SCM_R")
		)
		(pad "2" smd rect
			(at 0.889 0)
			(size 1.016 1.27)
			(layers "F.Cu" "F.Mask" "F.Paste")
			(net "GND")
		)
	)
	(footprint ""
		(layer "F.Cu")
		(at 118.11 -418.846 -90)
		(property "Reference" "R3434"
			(at 0 0 270)
			(layer "F.SilkS")
			(hide yes)
			(effects
				(font
					(size 1.27 1.27)
				)
			)
		)
		(property "Value" ""
			(at 0 0 270)
			(layer "F.Fab")
			(effects
				(font
					(size 1.27 1.27)
				)
			)
		)
		(duplicate_pad_numbers_are_jumpers no)
		(fp_line
			(start -0.7874 0.4064)
			(end -0.7874 -0.4064)
			(stroke
				(width 0.1524)
				(type default)
			)
			(layer "F.SilkS")
		)
		(fp_line
			(start 0.7874 0.4064)
			(end -0.7874 0.4064)
			(stroke
				(width 0.1524)
				(type default)
			)
			(layer "F.SilkS")
		)
		(fp_line
			(start -0.7874 -0.4064)
			(end 0.7874 -0.4064)
			(stroke
				(width 0.1524)
				(type default)
			)
			(layer "F.SilkS")
		)
		(fp_line
			(start 0.7874 -0.4064)
			(end 0.7874 0.4064)
			(stroke
				(width 0.1524)
				(type default)
			)
			(layer "F.SilkS")
		)
		(fp_line
			(start -0.67945 0.3048)
			(end -0.67945 -0.305054)
			(stroke
				(width 0.1)
				(type default)
			)
			(layer "F.Fab")
		)
		(fp_line
			(start -0.12065 0.3048)
			(end -0.67945 0.3048)
			(stroke
				(width 0.1)
				(type default)
			)
			(layer "F.Fab")
		)
		(fp_line
			(start 0.120396 0.3048)
			(end 0.120396 0.2794)
			(stroke
				(width 0.1)
				(type default)
			)
			(layer "F.Fab")
		)
		(fp_line
			(start 0.67945 0.3048)
			(end 0.120396 0.3048)
			(stroke
				(width 0.1)
				(type default)
			)
			(layer "F.Fab")
		)
		(fp_line
			(start -0.12065 0.2794)
			(end -0.12065 0.3048)
			(stroke
				(width 0.1)
				(type default)
			)
			(layer "F.Fab")
		)
		(fp_line
			(start 0.120396 0.2794)
			(end -0.12065 0.2794)
			(stroke
				(width 0.1)
				(type default)
			)
			(layer "F.Fab")
		)
		(fp_line
			(start -0.12065 -0.2794)
			(end 0.12065 -0.2794)
			(stroke
				(width 0.1)
				(type default)
			)
			(layer "F.Fab")
		)
		(fp_line
			(start 0.12065 -0.2794)
			(end 0.12065 -0.3048)
			(stroke
				(width 0.1)
				(type default)
			)
			(layer "F.Fab")
		)
		(fp_line
			(start 0.12065 -0.3048)
			(end 0.67945 -0.3048)
			(stroke
				(width 0.1)
				(type default)
			)
			(layer "F.Fab")
		)
		(fp_line
			(start 0.67945 -0.3048)
			(end 0.67945 0.3048)
			(stroke
				(width 0.1)
				(type default)
			)
			(layer "F.Fab")
		)
		(fp_line
			(start -0.67945 -0.305054)
			(end -0.12065 -0.305054)
			(stroke
				(width 0.1)
				(type default)
			)
			(layer "F.Fab")
		)
		(fp_line
			(start -0.12065 -0.305054)
			(end -0.12065 -0.2794)
			(stroke
				(width 0.1)
				(type default)
			)
			(layer "F.Fab")
		)
		(pad "1" smd circle
			(at -0.40005 0 270)
			(size 0 0)
			(layers "F.Cu" "F.Mask" "F.Paste")
			(net "P3V3_AUX")
		)
		(pad "2" smd circle
			(at 0.40005 0 270)
			(size 0 0)
			(layers "F.Cu" "F.Mask" "F.Paste")
			(net "GPU_HMC_PRSNT")
		)
	)
	(footprint ""
		(layer "F.Cu")
		(at 158.16707 -74.75347 90)
		(property "Reference" "R1005"
			(at 0 0 90)
			(layer "F.SilkS")
			(hide yes)
			(effects
				(font
					(size 1.27 1.27)
				)
			)
		)
		(property "Value" ""
			(at 0 0 90)
			(layer "F.Fab")
			(effects
				(font
					(size 1.27 1.27)
				)
			)
		)
		(duplicate_pad_numbers_are_jumpers no)
		(fp_line
			(start 0.7874 -0.4064)
			(end 0.7874 0.4064)
			(stroke
				(width 0.1524)
				(type default)
			)
			(layer "F.SilkS")
		)
		(fp_line
			(start -0.7874 -0.4064)
			(end 0.7874 -0.4064)
			(stroke
				(width 0.1524)
				(type default)
			)
			(layer "F.SilkS")
		)
		(fp_line
			(start 0.7874 0.4064)
			(end -0.7874 0.4064)
			(stroke
				(width 0.1524)
				(type default)
			)
			(layer "F.SilkS")
		)
		(fp_line
			(start -0.7874 0.4064)
			(end -0.7874 -0.4064)
			(stroke
				(width 0.1524)
				(type default)
			)
			(layer "F.SilkS")
		)
		(fp_line
			(start -0.12065 -0.305054)
			(end -0.12065 -0.2794)
			(stroke
				(width 0.1)
				(type default)
			)
			(layer "F.Fab")
		)
		(fp_line
			(start -0.67945 -0.305054)
			(end -0.12065 -0.305054)
			(stroke
				(width 0.1)
				(type default)
			)
			(layer "F.Fab")
		)
		(fp_line
			(start 0.67945 -0.3048)
			(end 0.67945 0.3048)
			(stroke
				(width 0.1)
				(type default)
			)
			(layer "F.Fab")
		)
		(fp_line
			(start 0.12065 -0.3048)
			(end 0.67945 -0.3048)
			(stroke
				(width 0.1)
				(type default)
			)
			(layer "F.Fab")
		)
		(fp_line
			(start 0.12065 -0.2794)
			(end 0.12065 -0.3048)
			(stroke
				(width 0.1)
				(type default)
			)
			(layer "F.Fab")
		)
		(fp_line
			(start -0.12065 -0.2794)
			(end 0.12065 -0.2794)
			(stroke
				(width 0.1)
				(type default)
			)
			(layer "F.Fab")
		)
		(fp_line
			(start 0.120396 0.2794)
			(end -0.12065 0.2794)
			(stroke
				(width 0.1)
				(type default)
			)
			(layer "F.Fab")
		)
		(fp_line
			(start -0.12065 0.2794)
			(end -0.12065 0.3048)
			(stroke
				(width 0.1)
				(type default)
			)
			(layer "F.Fab")
		)
		(fp_line
			(start 0.67945 0.3048)
			(end 0.120396 0.3048)
			(stroke
				(width 0.1)
				(type default)
			)
			(layer "F.Fab")
		)
		(fp_line
			(start 0.120396 0.3048)
			(end 0.120396 0.2794)
			(stroke
				(width 0.1)
				(type default)
			)
			(layer "F.Fab")
		)
		(fp_line
			(start -0.12065 0.3048)
			(end -0.67945 0.3048)
			(stroke
				(width 0.1)
				(type default)
			)
			(layer "F.Fab")
		)
		(fp_line
			(start -0.67945 0.3048)
			(end -0.67945 -0.305054)
			(stroke
				(width 0.1)
				(type default)
			)
			(layer "F.Fab")
		)
		(pad "1" smd circle
			(at -0.40005 0 90)
			(size 0 0)
			(layers "F.Cu" "F.Mask" "F.Paste")
			(net "M2_0_PEWAKE_R_N")
		)
		(pad "2" smd circle
			(at 0.40005 0 90)
			(size 0 0)
			(layers "F.Cu" "F.Mask" "F.Paste")
			(net "IRQ_LVC3_WAKE_N")
		)
	)
)
